FILE_TYPE = MACRO_DRAWING;
SET COLOR_WIRE YELLOW;
SET COLOR_PROP ORANGE;
SET COLOR_DOT WHITE;
SET COLOR_ARC YELLOW;
SET COLOR_BODY GREEN;
SET COLOR_NOTE PURPLE;
SET PROP_DISPLAY VALUE;
SET PAGE_NUMBER P134;
FORCEADD QUANTA_TITLE_BLOCK_C..1
(0 0);
FORCEPROP 1 LAST CUSTOM_TXT_CDS <NAME_2>
J 0
(-3175 50);
FORCEPROP 1 LAST CUSTOM_TXT_CDS <NAME_1>
J 0
(-3175 175);
FORCEPROP 1 LAST CUSTOM_TXT_CDS <Q_NUMBER>
J 0
(-1403 103);
DISPLAY 1.212766 (-1403 103);
FORCEPROP 1 LAST CUSTOM_TXT_CDS <Q_PROJ>
J 0
(-2382 102);
DISPLAY 1.212766 (-2382 102);
FORCEPROP 1 LAST CUSTOM_TXT_CDS <Q_REV>
J 0
(-184 103);
DISPLAY 1.212766 (-184 103);
FORCEPROP 1 LAST CUSTOM_TXT_CDS <CON_LAST_MODIFIED>
J 0
(-1885 15);
DISPLAY 0.978723 (-1885 15);
FORCEPROP 1 LAST CUSTOM_TXT_CDS <CON_PAGE_NUM> OF <CON_TOTAL_PAGES>
J 0
(-446 18);
DISPLAY 0.978723 (-446 18);
FORCEPROP 1 LAST Q_TITLE Blank
J 0
(-9275 75);
DISPLAY 2.446809 (-9275 75);
PAINT GREEN (-9275 75);
FORCEPROP 2 LAST PAGE_BORDER TRUE
J 0
(-7890 5250);
DISPLAY 0.638298 (-7890 5250);
PAINT PINK (-7890 5250);
DISPLAY INVISIBLE (-7890 5250);
FORCEPROP 2 LAST CDS_LIB pure_quanta
J 0
(0 0);
DISPLAY INVISIBLE (0 0);
FORCEPROP 1 LAST CDS_LMAN_SYM_OUTLINE -9475,6775,100,-125
J 0
(0 0);
DISPLAY 0.468085 (0 0);
PAINT GREEN (0 0);
DISPLAY INVISIBLE (0 0);
FORCEPROP 2 LAST CDS_XR_PAGE_TITLE CR-157 : @T6G_MB_LIB.T6G(SCH_1):PAGE157
J 0
(-7890 5250);
DISPLAY 0.638298 (-7890 5250);
PAINT PINK (-7890 5250);
DISPLAY INVISIBLE (-7890 5250);
FORCEPROP 2 LAST CUSTOM_TXT_CDS <XR_PAGE_TITLE>
J 0
(-7890 5250);
DISPLAY 0.638298 (-7890 5250);
PAINT PINK (-7890 5250);
DISPLAY INVISIBLE (-7890 5250);
FORCEPROP 1 LAST COMMENT_BODY TRUE
J 0
(12 -13);
DISPLAY 0.978723 (12 -13);
PAINT GREEN (12 -13);
DISPLAY INVISIBLE (12 -13);
FORCEPROP 1 LAST Q_DEPT BU9
J 1
(-3763 49);
DISPLAY 1.957447 (-3763 49);
PAINT GREEN (-3763 49);
DISPLAY INVISIBLE (-3763 49);
FORCEPROP 0 LAST CDS_CON_LAST_MODIFIED Thu Aug 24 10:14:43 2023
J 0
(-1885 15);
DISPLAY INVISIBLE (-1885 15);
QUIT
